# BASEBOARD_FAB2 (Tioga Pass) — schematic netlist excerpt (pin names and nets, part order shuffled) for the footprints in the layout excerpt that follows; sources: Cadence DE-HDL packaged netlist, KiCad conversion of Wiwynn_Tioga_Pass_MB.brd

R2N20  RES  0.0 5% CHIP  pkg 0402  page 138 : A = SMB_LAN_STBY_LVC3_SDA_R2 ; B = SMB_LAN_STBY_LVC3_SDA
C5G86  CAP_A  22.0UF 4V 20% X6S  pkg 0603V  page 243 : A = PVDDQ_GHJ ; B = GND
C7T4  CAP_A  47UF 4V 20% X5R  pkg 0603V  page 225 : A = PVDDQ_GHJ ; B = GND

(kicad_pcb
	(version 20260206)
	(generator "pcbnew")
	(generator_version "10.0")
	(general
		(thickness 1.6)
		(legacy_teardrops no)
	)
	(paper "A4")
	(title_block
		(title "Wiwynn_Tioga_Pass_MB.brd")
		(comment 1 "Tioga Pass / footprints 3372-3374 of 4770")
	)
	(layers
		(0 "F.Cu" signal "TOP")
		(4 "In1.Cu" signal "L2GND")
		(6 "In2.Cu" signal "L3")
		(8 "In3.Cu" signal "L4GND")
		(10 "In4.Cu" signal "L5")
		(12 "In5.Cu" signal "L6GND")
		(14 "In6.Cu" signal "L7VCC")
		(16 "In7.Cu" signal "L8VCC")
		(18 "In8.Cu" signal "L9GND")
		(20 "In9.Cu" signal "L10")
		(22 "In10.Cu" signal "L11GND")
		(24 "In11.Cu" signal "L12")
		(26 "In12.Cu" signal "L13GND")
		(2 "B.Cu" signal "BOTTOM")
		(9 "F.Adhes" user "F.Adhesive")
		(11 "B.Adhes" user "B.Adhesive")
		(13 "F.Paste" user "Package Geometry/Pastemask Top")
		(15 "B.Paste" user "Package Geometry/Pastemask Bottom")
		(5 "F.SilkS" user "Ref Des/Silkscreen Top")
		(7 "B.SilkS" user "Ref Des/Silkscreen Bottom")
		(1 "F.Mask" user "Board Geometry/Soldermask Top")
		(3 "B.Mask" user "Board Geometry/Soldermask Bottom")
		(17 "Dwgs.User" user "User.Drawings")
		(19 "Cmts.User" user "User.Comments")
		(21 "Eco1.User" user "User.Eco1")
		(23 "Eco2.User" user "User.Eco2")
		(25 "Edge.Cuts" user "Board Geometry/Outline")
		(27 "Margin" user)
		(31 "F.CrtYd" user "Package Geometry/Place Bound Top")
		(29 "B.CrtYd" user "Package Geometry/Place Bound Bottom")
		(35 "F.Fab" user "Ref Des/Assembly Top")
		(33 "B.Fab" user "Ref Des/Assembly Bottom")
	)
	(footprint ""
		(layer "B.Cu")
		(at 111.000032 -17.7546 90)
		(property "Reference" "C7T4"
			(at -1.848866 0.752348 90)
			(unlocked yes)
			(layer "B.SilkS")
			(effects
				(font
					(size 1.27 0.9652)
					(thickness 0.1524)
				)
				(justify mirror)
			)
		)
		(property "Value" ""
			(at 0 0 90)
			(layer "B.Fab")
			(effects
				(font
					(size 1.27 1.27)
				)
				(justify mirror)
			)
		)
		(duplicate_pad_numbers_are_jumpers no)
		(fp_rect
			(start 0.500126 1.598422)
			(end -0.500126 -0.201422)
			(stroke
				(width 0)
				(type default)
			)
			(fill no)
			(layer "B.CrtYd")
		)
		(fp_line
			(start 0.500126 -0.201422)
			(end -0.500126 -0.201422)
			(stroke
				(width 0.1)
				(type default)
			)
			(layer "B.Fab")
		)
		(fp_line
			(start -0.500126 -0.201422)
			(end -0.500126 1.598422)
			(stroke
				(width 0.1)
				(type default)
			)
			(layer "B.Fab")
		)
		(fp_line
			(start 0.500126 1.598422)
			(end 0.500126 -0.201422)
			(stroke
				(width 0.1)
				(type default)
			)
			(layer "B.Fab")
		)
		(fp_line
			(start -0.500126 1.598422)
			(end 0.500126 1.598422)
			(stroke
				(width 0.1)
				(type default)
			)
			(layer "B.Fab")
		)
		(pad "1" smd rect
			(at 0 0)
			(size 0.889 0.9906)
			(layers "B.Cu" "B.Mask" "B.Paste")
			(net "PVDDQ_GHJ")
		)
		(pad "2" smd rect
			(at 0 1.397)
			(size 0.889 0.9906)
			(layers "B.Cu" "B.Mask" "B.Paste")
			(net "GND")
		)
		(zone
			(layer "B.Cu")
			(hatch none 0.5)
			(connect_pads
				(clearance 0)
			)
			(min_thickness 0.25)
			(keepout
				(tracks allowed)
				(vias not_allowed)
				(pads allowed)
				(copperpour not_allowed)
				(footprints allowed)
			)
			(placement
				(enabled no)
				(sheetname "")
			)
			(fill
				(thermal_gap 0.5)
				(thermal_bridge_width 0.5)
				(island_removal_mode 0)
			)
			(polygon
				(pts
					(xy 111.952532 -18.2499) (xy 111.444532 -18.2499) (xy 111.444532 -17.2593) (xy 111.952532 -17.2593)
				)
			)
		)
		(zone
			(layer "B.Cu")
			(hatch none 0.5)
			(connect_pads
				(clearance 0)
			)
			(min_thickness 0.25)
			(keepout
				(tracks not_allowed)
				(vias allowed)
				(pads allowed)
				(copperpour not_allowed)
				(footprints allowed)
			)
			(placement
				(enabled no)
				(sheetname "")
			)
			(fill
				(thermal_gap 0.5)
				(thermal_bridge_width 0.5)
				(island_removal_mode 0)
			)
			(polygon
				(pts
					(xy 111.952532 -18.2499) (xy 111.444532 -18.2499) (xy 111.444532 -17.2593) (xy 111.952532 -17.2593)
				)
			)
		)
	)
	(footprint ""
		(layer "B.Cu")
		(at 87.158068 -3.3528 -90)
		(property "Reference" "C5G86"
			(at -1.14681 0.76708 0)
			(unlocked yes)
			(layer "B.SilkS")
			(effects
				(font
					(size 0.7874 0.5842)
					(thickness 0.1524)
				)
				(justify mirror)
			)
		)
		(property "Value" ""
			(at 0 0 90)
			(layer "B.Fab")
			(effects
				(font
					(size 1.27 1.27)
				)
				(justify mirror)
			)
		)
		(duplicate_pad_numbers_are_jumpers no)
		(fp_rect
			(start 0.4953 1.6002)
			(end -0.4953 -0.2032)
			(stroke
				(width 0)
				(type default)
			)
			(fill no)
			(layer "B.CrtYd")
		)
		(fp_line
			(start -0.4953 1.6002)
			(end 0.4953 1.6002)
			(stroke
				(width 0.1)
				(type default)
			)
			(layer "B.Fab")
		)
		(fp_line
			(start 0.4953 1.6002)
			(end 0.4953 -0.2032)
			(stroke
				(width 0.1)
				(type default)
			)
			(layer "B.Fab")
		)
		(fp_line
			(start -0.4953 -0.2032)
			(end -0.4953 1.6002)
			(stroke
				(width 0.1)
				(type default)
			)
			(layer "B.Fab")
		)
		(fp_line
			(start 0.4953 -0.2032)
			(end -0.4953 -0.2032)
			(stroke
				(width 0.1)
				(type default)
			)
			(layer "B.Fab")
		)
		(pad "1" smd rect
			(at 0 0 90)
			(size 0.762 0.889)
			(layers "B.Cu" "B.Mask" "B.Paste")
			(net "PVDDQ_GHJ")
		)
		(pad "2" smd rect
			(at 0 1.397 90)
			(size 0.762 0.889)
			(layers "B.Cu" "B.Mask" "B.Paste")
			(net "GND")
		)
		(zone
			(layer "B.Cu")
			(hatch none 0.5)
			(connect_pads
				(clearance 0)
			)
			(min_thickness 0.25)
			(keepout
				(tracks not_allowed)
				(vias allowed)
				(pads allowed)
				(copperpour not_allowed)
				(footprints allowed)
			)
			(placement
				(enabled no)
				(sheetname "")
			)
			(fill
				(thermal_gap 0.5)
				(thermal_bridge_width 0.5)
				(island_removal_mode 0)
			)
			(polygon
				(pts
					(xy 86.205568 -2.9718) (xy 86.713568 -2.9718) (xy 86.713568 -3.7338) (xy 86.205568 -3.7338)
				)
			)
		)
	)
	(footprint ""
		(layer "B.Cu")
		(at 394.589 -88.2015)
		(property "Reference" "R2N20"
			(at 0 0 0)
			(layer "B.SilkS")
			(hide yes)
			(effects
				(font
					(size 1.27 1.27)
				)
				(justify mirror)
			)
		)
		(property "Value" ""
			(at 0 0 0)
			(layer "B.Fab")
			(effects
				(font
					(size 1.27 1.27)
				)
				(justify mirror)
			)
		)
		(duplicate_pad_numbers_are_jumpers no)
		(fp_poly
			(pts
				(xy 0.2794 -0.1016) (xy -0.2794 -0.1016) (xy -0.2794 0.9906) (xy 0.2794 0.9906)
			)
			(stroke
				(width 0)
				(type default)
			)
			(fill no)
			(layer "B.CrtYd")
		)
		(fp_line
			(start -0.2794 -0.1016)
			(end 0.2794 -0.1016)
			(stroke
				(width 0.1)
				(type default)
			)
			(layer "B.Fab")
		)
		(fp_line
			(start -0.2794 0.9906)
			(end -0.2794 -0.1016)
			(stroke
				(width 0.1)
				(type default)
			)
			(layer "B.Fab")
		)
		(fp_line
			(start 0.2794 -0.1016)
			(end 0.2794 0.9906)
			(stroke
				(width 0.1)
				(type default)
			)
			(layer "B.Fab")
		)
		(fp_line
			(start 0.2794 0.9906)
			(end -0.2794 0.9906)
			(stroke
				(width 0.1)
				(type default)
			)
			(layer "B.Fab")
		)
		(pad "1" smd rect
			(at 0 0 180)
			(size 0.508 0.508)
			(layers "B.Cu" "B.Mask" "B.Paste")
			(net "SMB_LAN_STBY_LVC3_SDA_R2")
		)
		(pad "2" smd rect
			(at 0 0.889 180)
			(size 0.508 0.508)
			(layers "B.Cu" "B.Mask" "B.Paste")
			(net "SMB_LAN_STBY_LVC3_SDA")
		)
		(zone
			(layer "B.Cu")
			(hatch none 0.5)
			(connect_pads
				(clearance 0)
			)
			(min_thickness 0.25)
			(keepout
				(tracks allowed)
				(vias not_allowed)
				(pads allowed)
				(copperpour not_allowed)
				(footprints allowed)
			)
			(placement
				(enabled no)
				(sheetname "")
			)
			(fill
				(thermal_gap 0.5)
				(thermal_bridge_width 0.5)
				(island_removal_mode 0)
			)
			(polygon
				(pts
					(xy 394.843 -87.9475) (xy 394.335 -87.9475) (xy 394.335 -87.5665) (xy 394.843 -87.5665)
				)
			)
		)
		(zone
			(layer "B.Cu")
			(hatch none 0.5)
			(connect_pads
				(clearance 0)
			)
			(min_thickness 0.25)
			(keepout
				(tracks not_allowed)
				(vias allowed)
				(pads allowed)
				(copperpour not_allowed)
				(footprints allowed)
			)
			(placement
				(enabled no)
				(sheetname "")
			)
			(fill
				(thermal_gap 0.5)
				(thermal_bridge_width 0.5)
				(island_removal_mode 0)
			)
			(polygon
				(pts
					(xy 394.843 -87.5665) (xy 394.335 -87.5665) (xy 394.335 -87.9475) (xy 394.843 -87.9475)
				)
			)
		)
	)
)
